(kicad_pcb
	(version 20260206)
	(generator "pcbnew")
	(generator_version "10.0")
	(general
		(thickness 1.6)
		(legacy_teardrops no)
	)
	(paper "A4")
	(title_block
		(title "01162023_DA0F0TEBIF0_F0T_Expander_BD_F_brd_V02_OCP.brd")
		(comment 1 "Grand Teton / footprints 7982-7990 of 9728")
	)
	(layers
		(0 "F.Cu" signal "TOP")
		(4 "In1.Cu" signal "GND")
		(6 "In2.Cu" signal "VCC")
		(8 "In3.Cu" signal "VCC1")
		(10 "In4.Cu" signal "GND1")
		(12 "In5.Cu" signal "IN1")
		(14 "In6.Cu" signal "GND2")
		(16 "In7.Cu" signal "IN2")
		(18 "In8.Cu" signal "GND3")
		(20 "In9.Cu" signal "IN3")
		(22 "In10.Cu" signal "GND4")
		(24 "In11.Cu" signal "IN4")
		(26 "In12.Cu" signal "GND5")
		(28 "In13.Cu" signal "IN5")
		(30 "In14.Cu" signal "GND6")
		(32 "In15.Cu" signal "IN6")
		(34 "In16.Cu" signal "GND7")
		(2 "B.Cu" signal "BOTTOM")
		(9 "F.Adhes" user "F.Adhesive")
		(11 "B.Adhes" user "B.Adhesive")
		(13 "F.Paste" user "Package Geometry/Pastemask Top")
		(15 "B.Paste" user "Package Geometry/Pastemask Bottom")
		(5 "F.SilkS" user "Ref Des/Silkscreen Top")
		(7 "B.SilkS" user "Ref Des/Silkscreen Bottom")
		(1 "F.Mask" user "Board Geometry/Soldermask Top")
		(3 "B.Mask" user "Board Geometry/Soldermask Bottom")
		(17 "Dwgs.User" user "User.Drawings")
		(19 "Cmts.User" user "User.Comments")
		(21 "Eco1.User" user "User.Eco1")
		(23 "Eco2.User" user "User.Eco2")
		(25 "Edge.Cuts" user "Board Geometry/Outline")
		(27 "Margin" user)
		(31 "F.CrtYd" user "Package Geometry/Place Bound Top")
		(29 "B.CrtYd" user "Package Geometry/Place Bound Bottom")
		(35 "F.Fab" user "Ref Des/Assembly Top")
		(33 "B.Fab" user "Ref Des/Assembly Bottom")
	)
	(footprint ""
		(layer "B.Cu")
		(at 294.69969 -288.299906 90)
		(property "Reference" "C3287"
			(at 0 0 90)
			(layer "B.SilkS")
			(hide yes)
			(effects
				(font
					(size 1.27 1.27)
				)
				(justify mirror)
			)
		)
		(property "Value" ""
			(at 0 0 90)
			(layer "B.Fab")
			(effects
				(font
					(size 1.27 1.27)
				)
				(justify mirror)
			)
		)
		(duplicate_pad_numbers_are_jumpers no)
		(fp_line
			(start 0.299974 -0.150114)
			(end -0.299974 -0.150114)
			(stroke
				(width 0.1)
				(type default)
			)
			(layer "B.Fab")
		)
		(fp_line
			(start -0.299974 -0.150114)
			(end -0.299974 0.150114)
			(stroke
				(width 0.1)
				(type default)
			)
			(layer "B.Fab")
		)
		(fp_line
			(start 0.299974 0.150114)
			(end 0.299974 -0.150114)
			(stroke
				(width 0.1)
				(type default)
			)
			(layer "B.Fab")
		)
		(fp_line
			(start -0.299974 0.150114)
			(end 0.299974 0.150114)
			(stroke
				(width 0.1)
				(type default)
			)
			(layer "B.Fab")
		)
		(pad "1" smd rect
			(at 0.2667 0 270)
			(size 0.3048 0.381)
			(layers "B.Cu" "B.Mask" "B.Paste")
			(net "P1V25_PEX2")
		)
		(pad "2" smd rect
			(at -0.2667 0 270)
			(size 0.3048 0.381)
			(layers "B.Cu" "B.Mask" "B.Paste")
			(net "GND")
		)
	)
	(footprint ""
		(layer "B.Cu")
		(at 345.059 -233.553 90)
		(property "Reference" "R3564"
			(at 0 0 90)
			(layer "B.SilkS")
			(hide yes)
			(effects
				(font
					(size 1.27 1.27)
				)
				(justify mirror)
			)
		)
		(property "Value" ""
			(at 0 0 90)
			(layer "B.Fab")
			(effects
				(font
					(size 1.27 1.27)
				)
				(justify mirror)
			)
		)
		(duplicate_pad_numbers_are_jumpers no)
		(fp_line
			(start 0.7874 -0.4064)
			(end -0.7874 -0.4064)
			(stroke
				(width 0.1524)
				(type default)
			)
			(layer "B.SilkS")
		)
		(fp_line
			(start -0.7874 -0.4064)
			(end -0.7874 0.4064)
			(stroke
				(width 0.1524)
				(type default)
			)
			(layer "B.SilkS")
		)
		(fp_line
			(start 0.7874 0.4064)
			(end 0.7874 -0.4064)
			(stroke
				(width 0.1524)
				(type default)
			)
			(layer "B.SilkS")
		)
		(fp_line
			(start -0.7874 0.4064)
			(end 0.7874 0.4064)
			(stroke
				(width 0.1524)
				(type default)
			)
			(layer "B.SilkS")
		)
		(fp_line
			(start 0.67945 -0.305054)
			(end 0.12065 -0.305054)
			(stroke
				(width 0.1)
				(type default)
			)
			(layer "B.Fab")
		)
		(fp_line
			(start 0.12065 -0.305054)
			(end 0.12065 -0.2794)
			(stroke
				(width 0.1)
				(type default)
			)
			(layer "B.Fab")
		)
		(fp_line
			(start -0.12065 -0.3048)
			(end -0.67945 -0.3048)
			(stroke
				(width 0.1)
				(type default)
			)
			(layer "B.Fab")
		)
		(fp_line
			(start -0.67945 -0.3048)
			(end -0.67945 0.3048)
			(stroke
				(width 0.1)
				(type default)
			)
			(layer "B.Fab")
		)
		(fp_line
			(start 0.12065 -0.2794)
			(end -0.12065 -0.2794)
			(stroke
				(width 0.1)
				(type default)
			)
			(layer "B.Fab")
		)
		(fp_line
			(start -0.12065 -0.2794)
			(end -0.12065 -0.3048)
			(stroke
				(width 0.1)
				(type default)
			)
			(layer "B.Fab")
		)
		(fp_line
			(start 0.12065 0.2794)
			(end 0.12065 0.3048)
			(stroke
				(width 0.1)
				(type default)
			)
			(layer "B.Fab")
		)
		(fp_line
			(start -0.120396 0.2794)
			(end 0.12065 0.2794)
			(stroke
				(width 0.1)
				(type default)
			)
			(layer "B.Fab")
		)
		(fp_line
			(start 0.67945 0.3048)
			(end 0.67945 -0.305054)
			(stroke
				(width 0.1)
				(type default)
			)
			(layer "B.Fab")
		)
		(fp_line
			(start 0.12065 0.3048)
			(end 0.67945 0.3048)
			(stroke
				(width 0.1)
				(type default)
			)
			(layer "B.Fab")
		)
		(fp_line
			(start -0.120396 0.3048)
			(end -0.120396 0.2794)
			(stroke
				(width 0.1)
				(type default)
			)
			(layer "B.Fab")
		)
		(fp_line
			(start -0.67945 0.3048)
			(end -0.120396 0.3048)
			(stroke
				(width 0.1)
				(type default)
			)
			(layer "B.Fab")
		)
		(pad "1" smd circle
			(at 0.40005 0 270)
			(size 0 0)
			(layers "B.Cu" "B.Mask" "B.Paste")
			(net "SSD5_PWR_EN_R")
		)
		(pad "2" smd circle
			(at -0.40005 0 270)
			(size 0 0)
			(layers "B.Cu" "B.Mask" "B.Paste")
			(net "SSD5_PWR_EN")
		)
	)
	(footprint ""
		(layer "B.Cu")
		(at 350.58731 -257.699764 180)
		(property "Reference" "PC133"
			(at 0 0 0)
			(layer "B.SilkS")
			(hide yes)
			(effects
				(font
					(size 1.27 1.27)
				)
				(justify mirror)
			)
		)
		(property "Value" ""
			(at 0 0 0)
			(layer "B.Fab")
			(effects
				(font
					(size 1.27 1.27)
				)
				(justify mirror)
			)
		)
		(duplicate_pad_numbers_are_jumpers no)
		(fp_line
			(start 0.7874 0.4064)
			(end 0.7874 -0.4064)
			(stroke
				(width 0.1524)
				(type default)
			)
			(layer "B.SilkS")
		)
		(fp_line
			(start 0.7874 -0.4064)
			(end -0.7874 -0.4064)
			(stroke
				(width 0.1524)
				(type default)
			)
			(layer "B.SilkS")
		)
		(fp_line
			(start -0.7874 0.4064)
			(end 0.7874 0.4064)
			(stroke
				(width 0.1524)
				(type default)
			)
			(layer "B.SilkS")
		)
		(fp_line
			(start -0.7874 -0.4064)
			(end -0.7874 0.4064)
			(stroke
				(width 0.1524)
				(type default)
			)
			(layer "B.SilkS")
		)
		(fp_line
			(start 0.67945 0.3048)
			(end 0.67945 -0.305054)
			(stroke
				(width 0.1)
				(type default)
			)
			(layer "B.Fab")
		)
		(fp_line
			(start 0.67945 -0.305054)
			(end 0.12065 -0.305054)
			(stroke
				(width 0.1)
				(type default)
			)
			(layer "B.Fab")
		)
		(fp_line
			(start 0.12065 0.3048)
			(end 0.67945 0.3048)
			(stroke
				(width 0.1)
				(type default)
			)
			(layer "B.Fab")
		)
		(fp_line
			(start 0.12065 0.2794)
			(end 0.12065 0.3048)
			(stroke
				(width 0.1)
				(type default)
			)
			(layer "B.Fab")
		)
		(fp_line
			(start 0.12065 -0.2794)
			(end -0.12065 -0.2794)
			(stroke
				(width 0.1)
				(type default)
			)
			(layer "B.Fab")
		)
		(fp_line
			(start 0.12065 -0.305054)
			(end 0.12065 -0.2794)
			(stroke
				(width 0.1)
				(type default)
			)
			(layer "B.Fab")
		)
		(fp_line
			(start -0.120396 0.3048)
			(end -0.120396 0.2794)
			(stroke
				(width 0.1)
				(type default)
			)
			(layer "B.Fab")
		)
		(fp_line
			(start -0.120396 0.2794)
			(end 0.12065 0.2794)
			(stroke
				(width 0.1)
				(type default)
			)
			(layer "B.Fab")
		)
		(fp_line
			(start -0.12065 -0.2794)
			(end -0.12065 -0.3048)
			(stroke
				(width 0.1)
				(type default)
			)
			(layer "B.Fab")
		)
		(fp_line
			(start -0.12065 -0.3048)
			(end -0.67945 -0.3048)
			(stroke
				(width 0.1)
				(type default)
			)
			(layer "B.Fab")
		)
		(fp_line
			(start -0.67945 0.3048)
			(end -0.120396 0.3048)
			(stroke
				(width 0.1)
				(type default)
			)
			(layer "B.Fab")
		)
		(fp_line
			(start -0.67945 -0.3048)
			(end -0.67945 0.3048)
			(stroke
				(width 0.1)
				(type default)
			)
			(layer "B.Fab")
		)
		(pad "1" smd circle
			(at 0.40005 0)
			(size 0 0)
			(layers "B.Cu" "B.Mask" "B.Paste")
			(net "P0V8_PEX3_TSEN_R")
		)
		(pad "2" smd circle
			(at -0.40005 0)
			(size 0 0)
			(layers "B.Cu" "B.Mask" "B.Paste")
			(net "GND")
		)
	)
	(footprint ""
		(layer "B.Cu")
		(at 362.3691 -293.660068 90)
		(property "Reference" "PC184"
			(at 0 0 90)
			(layer "B.SilkS")
			(hide yes)
			(effects
				(font
					(size 1.27 1.27)
				)
				(justify mirror)
			)
		)
		(property "Value" ""
			(at 0 0 90)
			(layer "B.Fab")
			(effects
				(font
					(size 1.27 1.27)
				)
				(justify mirror)
			)
		)
		(duplicate_pad_numbers_are_jumpers no)
		(fp_line
			(start 4.84378 -2.150618)
			(end 4.53898 -2.150618)
			(stroke
				(width 0.1524)
				(type default)
			)
			(layer "B.SilkS")
		)
		(fp_line
			(start 4.84378 -2.150618)
			(end 4.842256 2.163064)
			(stroke
				(width 0.1524)
				(type default)
			)
			(layer "B.SilkS")
		)
		(fp_line
			(start 4.69138 -2.150618)
			(end 4.692396 2.161032)
			(stroke
				(width 0.1524)
				(type default)
			)
			(layer "B.SilkS")
		)
		(fp_line
			(start 4.53898 -2.150618)
			(end 4.539742 2.152142)
			(stroke
				(width 0.1524)
				(type default)
			)
			(layer "B.SilkS")
		)
		(fp_line
			(start 4.53898 -2.15011)
			(end -4.53898 -2.15011)
			(stroke
				(width 0.1524)
				(type default)
			)
			(layer "B.SilkS")
		)
		(fp_line
			(start -4.53898 -2.15011)
			(end -4.53898 2.15011)
			(stroke
				(width 0.1524)
				(type default)
			)
			(layer "B.SilkS")
		)
		(fp_line
			(start 4.53898 2.15011)
			(end 4.53898 -2.15011)
			(stroke
				(width 0.1524)
				(type default)
			)
			(layer "B.SilkS")
		)
		(fp_line
			(start -4.53898 2.15011)
			(end 4.53898 2.15011)
			(stroke
				(width 0.1524)
				(type default)
			)
			(layer "B.SilkS")
		)
		(fp_line
			(start 4.83108 2.150364)
			(end 4.447794 2.149348)
			(stroke
				(width 0.1524)
				(type default)
			)
			(layer "B.SilkS")
		)
		(fp_line
			(start 3.64998 -2.15011)
			(end -3.64998 -2.15011)
			(stroke
				(width 0.1)
				(type default)
			)
			(layer "B.Fab")
		)
		(fp_line
			(start -3.64998 -2.15011)
			(end -3.64998 2.15011)
			(stroke
				(width 0.1)
				(type default)
			)
			(layer "B.Fab")
		)
		(fp_line
			(start 3.64998 2.15011)
			(end 3.64998 -2.15011)
			(stroke
				(width 0.1)
				(type default)
			)
			(layer "B.Fab")
		)
		(fp_line
			(start -3.64998 2.15011)
			(end 3.64998 2.15011)
			(stroke
				(width 0.1)
				(type default)
			)
			(layer "B.Fab")
		)
		(fp_text user "+"
			(at 6.214872 -0.337058 90)
			(unlocked yes)
			(layer "B.SilkS")
			(effects
				(font
					(size 1.905 1.4224)
					(thickness 0.1524)
				)
				(justify left mirror)
			)
		)
		(fp_text user "-"
			(at -4.313174 -0.094488 90)
			(unlocked yes)
			(layer "B.SilkS")
			(effects
				(font
					(size 1.905 1.4224)
					(thickness 0.1524)
				)
				(justify left mirror)
			)
		)
		(fp_text user "+"
			(at 6.214872 -0.337058 90)
			(unlocked yes)
			(layer "B.Fab")
			(effects
				(font
					(size 1.905 1.4224)
					(thickness 0.1524)
				)
				(justify left mirror)
			)
		)
		(fp_text user "-"
			(at -4.313174 -0.094488 90)
			(unlocked yes)
			(layer "B.Fab")
			(effects
				(font
					(size 1.905 1.4224)
					(thickness 0.1524)
				)
				(justify left mirror)
			)
		)
		(pad "1" smd rect
			(at 3.199892 0 270)
			(size 2.413 2.8194)
			(layers "B.Cu" "B.Mask" "B.Paste")
			(net "P0V8_PEX3")
		)
		(pad "2" smd rect
			(at -3.199892 0 270)
			(size 2.413 2.8194)
			(layers "B.Cu" "B.Mask" "B.Paste")
			(net "GND")
		)
	)
	(footprint ""
		(layer "B.Cu")
		(at 189.500002 -109.251496)
		(property "Reference" "C893"
			(at 0 0 0)
			(layer "B.SilkS")
			(hide yes)
			(effects
				(font
					(size 1.27 1.27)
				)
				(justify mirror)
			)
		)
		(property "Value" ""
			(at 0 0 0)
			(layer "B.Fab")
			(effects
				(font
					(size 1.27 1.27)
				)
				(justify mirror)
			)
		)
		(duplicate_pad_numbers_are_jumpers no)
		(fp_line
			(start -0.299974 -0.150114)
			(end -0.299974 0.150114)
			(stroke
				(width 0.1)
				(type default)
			)
			(layer "B.Fab")
		)
		(fp_line
			(start -0.299974 0.150114)
			(end 0.299974 0.150114)
			(stroke
				(width 0.1)
				(type default)
			)
			(layer "B.Fab")
		)
		(fp_line
			(start 0.299974 -0.150114)
			(end -0.299974 -0.150114)
			(stroke
				(width 0.1)
				(type default)
			)
			(layer "B.Fab")
		)
		(fp_line
			(start 0.299974 0.150114)
			(end 0.299974 -0.150114)
			(stroke
				(width 0.1)
				(type default)
			)
			(layer "B.Fab")
		)
		(pad "1" smd rect
			(at 0.2667 0 180)
			(size 0.3048 0.381)
			(layers "B.Cu" "B.Mask" "B.Paste")
			(net "P12V_NIC3")
		)
		(pad "2" smd rect
			(at -0.2667 0 180)
			(size 0.3048 0.381)
			(layers "B.Cu" "B.Mask" "B.Paste")
			(net "GND")
		)
	)
	(footprint ""
		(layer "B.Cu")
		(at 161.964116 -145.284952 180)
		(property "Reference" "C881"
			(at 0 0 0)
			(layer "B.SilkS")
			(hide yes)
			(effects
				(font
					(size 1.27 1.27)
				)
				(justify mirror)
			)
		)
		(property "Value" ""
			(at 0 0 0)
			(layer "B.Fab")
			(effects
				(font
					(size 1.27 1.27)
				)
				(justify mirror)
			)
		)
		(duplicate_pad_numbers_are_jumpers no)
		(fp_line
			(start 0.299974 0.150114)
			(end 0.299974 -0.150114)
			(stroke
				(width 0.1)
				(type default)
			)
			(layer "B.Fab")
		)
		(fp_line
			(start 0.299974 -0.150114)
			(end -0.299974 -0.150114)
			(stroke
				(width 0.1)
				(type default)
			)
			(layer "B.Fab")
		)
		(fp_line
			(start -0.299974 0.150114)
			(end 0.299974 0.150114)
			(stroke
				(width 0.1)
				(type default)
			)
			(layer "B.Fab")
		)
		(fp_line
			(start -0.299974 -0.150114)
			(end -0.299974 0.150114)
			(stroke
				(width 0.1)
				(type default)
			)
			(layer "B.Fab")
		)
		(pad "1" smd rect
			(at 0.2667 0)
			(size 0.3048 0.381)
			(layers "B.Cu" "B.Mask" "B.Paste")
			(net "P12V_NIC2")
		)
		(pad "2" smd rect
			(at -0.2667 0)
			(size 0.3048 0.381)
			(layers "B.Cu" "B.Mask" "B.Paste")
			(net "GND")
		)
	)
	(footprint ""
		(layer "B.Cu")
		(at 61.074808 -286.399732 90)
		(property "Reference" "C2960"
			(at 0 0 90)
			(layer "B.SilkS")
			(hide yes)
			(effects
				(font
					(size 1.27 1.27)
				)
				(justify mirror)
			)
		)
		(property "Value" ""
			(at 0 0 90)
			(layer "B.Fab")
			(effects
				(font
					(size 1.27 1.27)
				)
				(justify mirror)
			)
		)
		(duplicate_pad_numbers_are_jumpers no)
		(fp_line
			(start 0.299974 -0.150114)
			(end -0.299974 -0.150114)
			(stroke
				(width 0.1)
				(type default)
			)
			(layer "B.Fab")
		)
		(fp_line
			(start -0.299974 -0.150114)
			(end -0.299974 0.150114)
			(stroke
				(width 0.1)
				(type default)
			)
			(layer "B.Fab")
		)
		(fp_line
			(start 0.299974 0.150114)
			(end 0.299974 -0.150114)
			(stroke
				(width 0.1)
				(type default)
			)
			(layer "B.Fab")
		)
		(fp_line
			(start -0.299974 0.150114)
			(end 0.299974 0.150114)
			(stroke
				(width 0.1)
				(type default)
			)
			(layer "B.Fab")
		)
		(pad "1" smd rect
			(at 0.2667 0 270)
			(size 0.3048 0.381)
			(layers "B.Cu" "B.Mask" "B.Paste")
			(net "P1V25_SERDES_VDDPLL_PEX0")
		)
		(pad "2" smd rect
			(at -0.2667 0 270)
			(size 0.3048 0.381)
			(layers "B.Cu" "B.Mask" "B.Paste")
			(net "GND")
		)
	)
	(footprint ""
		(layer "B.Cu")
		(at 406.049988 -290.199826 90)
		(property "Reference" "C1971"
			(at 0 0 90)
			(layer "B.SilkS")
			(hide yes)
			(effects
				(font
					(size 1.27 1.27)
				)
				(justify mirror)
			)
		)
		(property "Value" ""
			(at 0 0 90)
			(layer "B.Fab")
			(effects
				(font
					(size 1.27 1.27)
				)
				(justify mirror)
			)
		)
		(duplicate_pad_numbers_are_jumpers no)
		(fp_line
			(start 0.299974 -0.150114)
			(end -0.299974 -0.150114)
			(stroke
				(width 0.1)
				(type default)
			)
			(layer "B.Fab")
		)
		(fp_line
			(start -0.299974 -0.150114)
			(end -0.299974 0.150114)
			(stroke
				(width 0.1)
				(type default)
			)
			(layer "B.Fab")
		)
		(fp_line
			(start 0.299974 0.150114)
			(end 0.299974 -0.150114)
			(stroke
				(width 0.1)
				(type default)
			)
			(layer "B.Fab")
		)
		(fp_line
			(start -0.299974 0.150114)
			(end 0.299974 0.150114)
			(stroke
				(width 0.1)
				(type default)
			)
			(layer "B.Fab")
		)
		(pad "1" smd rect
			(at 0.2667 0 270)
			(size 0.3048 0.381)
			(layers "B.Cu" "B.Mask" "B.Paste")
			(net "P0V8_SERDES_VDDA_PEX3")
		)
		(pad "2" smd rect
			(at -0.2667 0 270)
			(size 0.3048 0.381)
			(layers "B.Cu" "B.Mask" "B.Paste")
			(net "GND")
		)
	)
	(footprint ""
		(layer "B.Cu")
		(at 149.352254 -207.784192 -90)
		(property "Reference" "R980"
			(at 0 0 90)
			(layer "B.SilkS")
			(hide yes)
			(effects
				(font
					(size 1.27 1.27)
				)
				(justify mirror)
			)
		)
		(property "Value" ""
			(at 0 0 90)
			(layer "B.Fab")
			(effects
				(font
					(size 1.27 1.27)
				)
				(justify mirror)
			)
		)
		(duplicate_pad_numbers_are_jumpers no)
		(fp_line
			(start -0.7874 0.4064)
			(end 0.7874 0.4064)
			(stroke
				(width 0.1524)
				(type default)
			)
			(layer "B.SilkS")
		)
		(fp_line
			(start 0.7874 0.4064)
			(end 0.7874 -0.4064)
			(stroke
				(width 0.1524)
				(type default)
			)
			(layer "B.SilkS")
		)
		(fp_line
			(start -0.7874 -0.4064)
			(end -0.7874 0.4064)
			(stroke
				(width 0.1524)
				(type default)
			)
			(layer "B.SilkS")
		)
		(fp_line
			(start 0.7874 -0.4064)
			(end -0.7874 -0.4064)
			(stroke
				(width 0.1524)
				(type default)
			)
			(layer "B.SilkS")
		)
		(fp_line
			(start -0.67945 0.3048)
			(end -0.120396 0.3048)
			(stroke
				(width 0.1)
				(type default)
			)
			(layer "B.Fab")
		)
		(fp_line
			(start -0.120396 0.3048)
			(end -0.120396 0.2794)
			(stroke
				(width 0.1)
				(type default)
			)
			(layer "B.Fab")
		)
		(fp_line
			(start 0.12065 0.3048)
			(end 0.67945 0.3048)
			(stroke
				(width 0.1)
				(type default)
			)
			(layer "B.Fab")
		)
		(fp_line
			(start 0.67945 0.3048)
			(end 0.67945 -0.305054)
			(stroke
				(width 0.1)
				(type default)
			)
			(layer "B.Fab")
		)
		(fp_line
			(start -0.120396 0.2794)
			(end 0.12065 0.2794)
			(stroke
				(width 0.1)
				(type default)
			)
			(layer "B.Fab")
		)
		(fp_line
			(start 0.12065 0.2794)
			(end 0.12065 0.3048)
			(stroke
				(width 0.1)
				(type default)
			)
			(layer "B.Fab")
		)
		(fp_line
			(start -0.12065 -0.2794)
			(end -0.12065 -0.3048)
			(stroke
				(width 0.1)
				(type default)
			)
			(layer "B.Fab")
		)
		(fp_line
			(start 0.12065 -0.2794)
			(end -0.12065 -0.2794)
			(stroke
				(width 0.1)
				(type default)
			)
			(layer "B.Fab")
		)
		(fp_line
			(start -0.67945 -0.3048)
			(end -0.67945 0.3048)
			(stroke
				(width 0.1)
				(type default)
			)
			(layer "B.Fab")
		)
		(fp_line
			(start -0.12065 -0.3048)
			(end -0.67945 -0.3048)
			(stroke
				(width 0.1)
				(type default)
			)
			(layer "B.Fab")
		)
		(fp_line
			(start 0.12065 -0.305054)
			(end 0.12065 -0.2794)
			(stroke
				(width 0.1)
				(type default)
			)
			(layer "B.Fab")
		)
		(fp_line
			(start 0.67945 -0.305054)
			(end 0.12065 -0.305054)
			(stroke
				(width 0.1)
				(type default)
			)
			(layer "B.Fab")
		)
		(pad "1" smd circle
			(at 0.40005 0 90)
			(size 0 0)
			(layers "B.Cu" "B.Mask" "B.Paste")
			(net "UART_PEX0_CLI_BUF_R_RX")
		)
		(pad "2" smd circle
			(at -0.40005 0 90)
			(size 0 0)
			(layers "B.Cu" "B.Mask" "B.Paste")
			(net "UART_PEX0_CLI_BUF_RX")
		)
	)
)
